# T6G (Grand Teton) — schematic parts with pin connectivity, parts 2285–2388 of 8303; source: Cadence DE-HDL packaged netlist (pstxprt.dat, pstxnet.dat, pstchip.dat)

C6669  Q_CAP_DIFFBUS  DIFF BUS_0.22UF 6.3V 20% X6S  pkg C0201  page 330 : 1 = P5E_CPU1_P1_TX_BUF_C_DP<4> ; 2 = P5E_CPU1_P1_TX_BUF_DP<4>
C6670  Q_CAP_DIFFBUS  DIFF BUS_0.22UF 6.3V 20% X6S  pkg C0201  page 330 : 1 = P5E_CPU1_P1_TX_BUF_C_DN<4> ; 2 = P5E_CPU1_P1_TX_BUF_DN<4>
C6671  Q_CAP_DIFFBUS  DIFF BUS_0.22UF 6.3V 20% X6S  pkg C0201  page 330 : 1 = P5E_CPU1_P1_TX_BUF_C_DP<5> ; 2 = P5E_CPU1_P1_TX_BUF_DP<5>
C6672  Q_CAP_DIFFBUS  DIFF BUS_0.22UF 6.3V 20% X6S  pkg C0201  page 330 : 1 = P5E_CPU1_P1_TX_BUF_C_DN<5> ; 2 = P5E_CPU1_P1_TX_BUF_DN<5>
C6673  Q_CAP_DIFFBUS  DIFF BUS_0.22UF 6.3V 20% X6S  pkg C0201  page 330 : 1 = P5E_CPU1_P1_TX_BUF_C_DP<6> ; 2 = P5E_CPU1_P1_TX_BUF_DP<6>
C6674  Q_CAP_DIFFBUS  DIFF BUS_0.22UF 6.3V 20% X6S  pkg C0201  page 330 : 1 = P5E_CPU1_P1_TX_BUF_C_DN<6> ; 2 = P5E_CPU1_P1_TX_BUF_DN<6>
C6675  Q_CAP_DIFFBUS  DIFF BUS_0.22UF 6.3V 20% X6S  pkg C0201  page 330 : 1 = P5E_CPU1_P1_TX_BUF_C_DP<7> ; 2 = P5E_CPU1_P1_TX_BUF_DP<7>
C6676  Q_CAP_DIFFBUS  DIFF BUS_0.22UF 6.3V 20% X6S  pkg C0201  page 330 : 1 = P5E_CPU1_P1_TX_BUF_C_DN<7> ; 2 = P5E_CPU1_P1_TX_BUF_DN<7>
C6677  Q_CAP_DIFFBUS  DIFF BUS_0.22UF 6.3V 20% X6S  pkg C0201  page 330 : 1 = P5E_CPU1_P1_TX_BUF_C_DP<8> ; 2 = P5E_CPU1_P1_TX_BUF_DP<8>
C6678  Q_CAP_DIFFBUS  DIFF BUS_0.22UF 6.3V 20% X6S  pkg C0201  page 330 : 1 = P5E_CPU1_P1_TX_BUF_C_DN<8> ; 2 = P5E_CPU1_P1_TX_BUF_DN<8>
C6679  Q_CAP_DIFFBUS  DIFF BUS_0.22UF 6.3V 20% X6S  pkg C0201  page 330 : 1 = P5E_CPU1_P1_TX_BUF_C_DP<9> ; 2 = P5E_CPU1_P1_TX_BUF_DP<9>
C6680  Q_CAP_DIFFBUS  DIFF BUS_0.22UF 6.3V 20% X6S  pkg C0201  page 330 : 1 = P5E_CPU1_P1_TX_BUF_C_DN<9> ; 2 = P5E_CPU1_P1_TX_BUF_DN<9>
C6681  Q_CAP_DIFFBUS  DIFF BUS_0.22UF 6.3V 20% X6S  pkg C0201  page 330 : 1 = P5E_CPU1_P1_TX_BUF_C_DP<10> ; 2 = P5E_CPU1_P1_TX_BUF_DP<10>
C6682  Q_CAP_DIFFBUS  DIFF BUS_0.22UF 6.3V 20% X6S  pkg C0201  page 330 : 1 = P5E_CPU1_P1_TX_BUF_C_DN<10> ; 2 = P5E_CPU1_P1_TX_BUF_DN<10>
C6683  Q_CAP_DIFFBUS  DIFF BUS_0.22UF 6.3V 20% X6S  pkg C0201  page 330 : 1 = P5E_CPU1_P1_TX_BUF_C_DP<11> ; 2 = P5E_CPU1_P1_TX_BUF_DP<11>
C6684  Q_CAP_DIFFBUS  DIFF BUS_0.22UF 6.3V 20% X6S  pkg C0201  page 330 : 1 = P5E_CPU1_P1_TX_BUF_C_DN<11> ; 2 = P5E_CPU1_P1_TX_BUF_DN<11>
C6685  Q_CAP_DIFFBUS  DIFF BUS_0.22UF 6.3V 20% X6S  pkg C0201  page 330 : 1 = P5E_CPU1_P1_TX_BUF_C_DP<12> ; 2 = P5E_CPU1_P1_TX_BUF_DP<12>
C6686  Q_CAP_DIFFBUS  DIFF BUS_0.22UF 6.3V 20% X6S  pkg C0201  page 330 : 1 = P5E_CPU1_P1_TX_BUF_C_DN<12> ; 2 = P5E_CPU1_P1_TX_BUF_DN<12>
C6687  Q_CAP_DIFFBUS  DIFF BUS_0.22UF 6.3V 20% X6S  pkg C0201  page 330 : 1 = P5E_CPU1_P1_TX_BUF_C_DP<13> ; 2 = P5E_CPU1_P1_TX_BUF_DP<13>
C6688  Q_CAP_DIFFBUS  DIFF BUS_0.22UF 6.3V 20% X6S  pkg C0201  page 330 : 1 = P5E_CPU1_P1_TX_BUF_C_DN<13> ; 2 = P5E_CPU1_P1_TX_BUF_DN<13>
C6689  Q_CAP_DIFFBUS  DIFF BUS_0.22UF 6.3V 20% X6S  pkg C0201  page 330 : 1 = P5E_CPU1_P1_TX_BUF_C_DP<14> ; 2 = P5E_CPU1_P1_TX_BUF_DP<14>
C6690  Q_CAP_DIFFBUS  DIFF BUS_0.22UF 6.3V 20% X6S  pkg C0201  page 330 : 1 = P5E_CPU1_P1_TX_BUF_C_DN<14> ; 2 = P5E_CPU1_P1_TX_BUF_DN<14>
C6691  Q_CAP_DIFFBUS  DIFF BUS_0.22UF 6.3V 20% X6S  pkg C0201  page 330 : 1 = P5E_CPU1_P1_TX_BUF_C_DP<15> ; 2 = P5E_CPU1_P1_TX_BUF_DP<15>
C6692  Q_CAP_DIFFBUS  DIFF BUS_0.22UF 6.3V 20% X6S  pkg C0201  page 330 : 1 = P5E_CPU1_P1_TX_BUF_C_DN<15> ; 2 = P5E_CPU1_P1_TX_BUF_DN<15>
C6693  Q_CAP_DIFFBUS  DIFF BUS_0.22UF 6.3V 20% X6S  pkg C0201  page 341 : 1 = P5E_CPU1_P2_TX_BUF_C_DP<0> ; 2 = P5E_CPU1_P2_TX_BUF_DP<0>
C6694  Q_CAP_DIFFBUS  DIFF BUS_0.22UF 6.3V 20% X6S  pkg C0201  page 341 : 1 = P5E_CPU1_P2_TX_BUF_C_DN<0> ; 2 = P5E_CPU1_P2_TX_BUF_DN<0>
C6695  Q_CAP_DIFFBUS  DIFF BUS_0.22UF 6.3V 20% X6S  pkg C0201  page 341 : 1 = P5E_CPU1_P2_TX_BUF_C_DP<1> ; 2 = P5E_CPU1_P2_TX_BUF_DP<1>
C6696  Q_CAP_DIFFBUS  DIFF BUS_0.22UF 6.3V 20% X6S  pkg C0201  page 341 : 1 = P5E_CPU1_P2_TX_BUF_C_DN<1> ; 2 = P5E_CPU1_P2_TX_BUF_DN<1>
C6697  Q_CAP_DIFFBUS  DIFF BUS_0.22UF 6.3V 20% X6S  pkg C0201  page 341 : 1 = P5E_CPU1_P2_TX_BUF_C_DP<2> ; 2 = P5E_CPU1_P2_TX_BUF_DP<2>
C6698  Q_CAP_DIFFBUS  DIFF BUS_0.22UF 6.3V 20% X6S  pkg C0201  page 341 : 1 = P5E_CPU1_P2_TX_BUF_C_DN<2> ; 2 = P5E_CPU1_P2_TX_BUF_DN<2>
C6699  Q_CAP_DIFFBUS  DIFF BUS_0.22UF 6.3V 20% X6S  pkg C0201  page 341 : 1 = P5E_CPU1_P2_TX_BUF_C_DP<3> ; 2 = P5E_CPU1_P2_TX_BUF_DP<3>
C6700  Q_CAP_DIFFBUS  DIFF BUS_0.22UF 6.3V 20% X6S  pkg C0201  page 341 : 1 = P5E_CPU1_P2_TX_BUF_C_DN<3> ; 2 = P5E_CPU1_P2_TX_BUF_DN<3>
C6701  Q_CAP_DIFFBUS  DIFF BUS_0.22UF 6.3V 20% X6S  pkg C0201  page 341 : 1 = P5E_CPU1_P2_TX_BUF_C_DP<4> ; 2 = P5E_CPU1_P2_TX_BUF_DP<4>
C6702  Q_CAP_DIFFBUS  DIFF BUS_0.22UF 6.3V 20% X6S  pkg C0201  page 341 : 1 = P5E_CPU1_P2_TX_BUF_C_DN<4> ; 2 = P5E_CPU1_P2_TX_BUF_DN<4>
C6703  Q_CAP_DIFFBUS  DIFF BUS_0.22UF 6.3V 20% X6S  pkg C0201  page 341 : 1 = P5E_CPU1_P2_TX_BUF_C_DP<5> ; 2 = P5E_CPU1_P2_TX_BUF_DP<5>
C6704  Q_CAP_DIFFBUS  DIFF BUS_0.22UF 6.3V 20% X6S  pkg C0201  page 341 : 1 = P5E_CPU1_P2_TX_BUF_C_DN<5> ; 2 = P5E_CPU1_P2_TX_BUF_DN<5>
C6705  Q_CAP_DIFFBUS  DIFF BUS_0.22UF 6.3V 20% X6S  pkg C0201  page 341 : 1 = P5E_CPU1_P2_TX_BUF_C_DP<6> ; 2 = P5E_CPU1_P2_TX_BUF_DP<6>
C6706  Q_CAP_DIFFBUS  DIFF BUS_0.22UF 6.3V 20% X6S  pkg C0201  page 341 : 1 = P5E_CPU1_P2_TX_BUF_C_DN<6> ; 2 = P5E_CPU1_P2_TX_BUF_DN<6>
C6707  Q_CAP_DIFFBUS  DIFF BUS_0.22UF 6.3V 20% X6S  pkg C0201  page 341 : 1 = P5E_CPU1_P2_TX_BUF_C_DP<7> ; 2 = P5E_CPU1_P2_TX_BUF_DP<7>
C6708  Q_CAP_DIFFBUS  DIFF BUS_0.22UF 6.3V 20% X6S  pkg C0201  page 341 : 1 = P5E_CPU1_P2_TX_BUF_C_DN<7> ; 2 = P5E_CPU1_P2_TX_BUF_DN<7>
C6709  Q_CAP_DIFFBUS  DIFF BUS_0.22UF 6.3V 20% X6S  pkg C0201  page 341 : 1 = P5E_CPU1_P2_TX_BUF_C_DP<8> ; 2 = P5E_CPU1_P2_TX_BUF_DP<8>
C6710  Q_CAP_DIFFBUS  DIFF BUS_0.22UF 6.3V 20% X6S  pkg C0201  page 341 : 1 = P5E_CPU1_P2_TX_BUF_C_DN<8> ; 2 = P5E_CPU1_P2_TX_BUF_DN<8>
C6711  Q_CAP_DIFFBUS  DIFF BUS_0.22UF 6.3V 20% X6S  pkg C0201  page 341 : 1 = P5E_CPU1_P2_TX_BUF_C_DP<9> ; 2 = P5E_CPU1_P2_TX_BUF_DP<9>
C6712  Q_CAP_DIFFBUS  DIFF BUS_0.22UF 6.3V 20% X6S  pkg C0201  page 341 : 1 = P5E_CPU1_P2_TX_BUF_C_DN<9> ; 2 = P5E_CPU1_P2_TX_BUF_DN<9>
C6713  Q_CAP_DIFFBUS  DIFF BUS_0.22UF 6.3V 20% X6S  pkg C0201  page 341 : 1 = P5E_CPU1_P2_TX_BUF_C_DP<10> ; 2 = P5E_CPU1_P2_TX_BUF_DP<10>
C6714  Q_CAP_DIFFBUS  DIFF BUS_0.22UF 6.3V 20% X6S  pkg C0201  page 341 : 1 = P5E_CPU1_P2_TX_BUF_C_DN<10> ; 2 = P5E_CPU1_P2_TX_BUF_DN<10>
C6715  Q_CAP_DIFFBUS  DIFF BUS_0.22UF 6.3V 20% X6S  pkg C0201  page 341 : 1 = P5E_CPU1_P2_TX_BUF_C_DP<11> ; 2 = P5E_CPU1_P2_TX_BUF_DP<11>
C6716  Q_CAP_DIFFBUS  DIFF BUS_0.22UF 6.3V 20% X6S  pkg C0201  page 341 : 1 = P5E_CPU1_P2_TX_BUF_C_DN<11> ; 2 = P5E_CPU1_P2_TX_BUF_DN<11>
C6717  Q_CAP_DIFFBUS  DIFF BUS_0.22UF 6.3V 20% X6S  pkg C0201  page 341 : 1 = P5E_CPU1_P2_TX_BUF_C_DP<12> ; 2 = P5E_CPU1_P2_TX_BUF_DP<12>
C6718  Q_CAP_DIFFBUS  DIFF BUS_0.22UF 6.3V 20% X6S  pkg C0201  page 341 : 1 = P5E_CPU1_P2_TX_BUF_C_DN<12> ; 2 = P5E_CPU1_P2_TX_BUF_DN<12>
C6719  Q_CAP_DIFFBUS  DIFF BUS_0.22UF 6.3V 20% X6S  pkg C0201  page 341 : 1 = P5E_CPU1_P2_TX_BUF_C_DP<13> ; 2 = P5E_CPU1_P2_TX_BUF_DP<13>
C6720  Q_CAP_DIFFBUS  DIFF BUS_0.22UF 6.3V 20% X6S  pkg C0201  page 341 : 1 = P5E_CPU1_P2_TX_BUF_C_DN<13> ; 2 = P5E_CPU1_P2_TX_BUF_DN<13>
C6721  Q_CAP_DIFFBUS  DIFF BUS_0.22UF 6.3V 20% X6S  pkg C0201  page 341 : 1 = P5E_CPU1_P2_TX_BUF_C_DP<14> ; 2 = P5E_CPU1_P2_TX_BUF_DP<14>
C6722  Q_CAP_DIFFBUS  DIFF BUS_0.22UF 6.3V 20% X6S  pkg C0201  page 341 : 1 = P5E_CPU1_P2_TX_BUF_C_DN<14> ; 2 = P5E_CPU1_P2_TX_BUF_DN<14>
C6723  Q_CAP_DIFFBUS  DIFF BUS_0.22UF 6.3V 20% X6S  pkg C0201  page 341 : 1 = P5E_CPU1_P2_TX_BUF_C_DP<15> ; 2 = P5E_CPU1_P2_TX_BUF_DP<15>
C6724  Q_CAP_DIFFBUS  DIFF BUS_0.22UF 6.3V 20% X6S  pkg C0201  page 341 : 1 = P5E_CPU1_P2_TX_BUF_C_DN<15> ; 2 = P5E_CPU1_P2_TX_BUF_DN<15>
C6725  Q_CAP_DIFFBUS  DIFF BUS_0.22UF 6.3V 20% X6S  pkg C0201  page 352 : 1 = P5E_CPU1_P3_TX_BUF_C_DP<0> ; 2 = P5E_CPU1_P3_TX_BUF_DP<0>
C6726  Q_CAP_DIFFBUS  DIFF BUS_0.22UF 6.3V 20% X6S  pkg C0201  page 352 : 1 = P5E_CPU1_P3_TX_BUF_C_DN<0> ; 2 = P5E_CPU1_P3_TX_BUF_DN<0>
C6727  Q_CAP_DIFFBUS  DIFF BUS_0.22UF 6.3V 20% X6S  pkg C0201  page 352 : 1 = P5E_CPU1_P3_TX_BUF_C_DP<1> ; 2 = P5E_CPU1_P3_TX_BUF_DP<1>
C6728  Q_CAP_DIFFBUS  DIFF BUS_0.22UF 6.3V 20% X6S  pkg C0201  page 352 : 1 = P5E_CPU1_P3_TX_BUF_C_DN<1> ; 2 = P5E_CPU1_P3_TX_BUF_DN<1>
C6729  Q_CAP_DIFFBUS  DIFF BUS_0.22UF 6.3V 20% X6S  pkg C0201  page 352 : 1 = P5E_CPU1_P3_TX_BUF_C_DP<2> ; 2 = P5E_CPU1_P3_TX_BUF_DP<2>
C6730  Q_CAP_DIFFBUS  DIFF BUS_0.22UF 6.3V 20% X6S  pkg C0201  page 352 : 1 = P5E_CPU1_P3_TX_BUF_C_DN<2> ; 2 = P5E_CPU1_P3_TX_BUF_DN<2>
C6731  Q_CAP_DIFFBUS  DIFF BUS_0.22UF 6.3V 20% X6S  pkg C0201  page 352 : 1 = P5E_CPU1_P3_TX_BUF_C_DP<3> ; 2 = P5E_CPU1_P3_TX_BUF_DP<3>
C6732  Q_CAP_DIFFBUS  DIFF BUS_0.22UF 6.3V 20% X6S  pkg C0201  page 352 : 1 = P5E_CPU1_P3_TX_BUF_C_DN<3> ; 2 = P5E_CPU1_P3_TX_BUF_DN<3>
C6733  Q_CAP_DIFFBUS  DIFF BUS_0.22UF 6.3V 20% X6S  pkg C0201  page 352 : 1 = P5E_CPU1_P3_TX_BUF_C_DP<4> ; 2 = P5E_CPU1_P3_TX_BUF_DP<4>
C6734  Q_CAP_DIFFBUS  DIFF BUS_0.22UF 6.3V 20% X6S  pkg C0201  page 352 : 1 = P5E_CPU1_P3_TX_BUF_C_DN<4> ; 2 = P5E_CPU1_P3_TX_BUF_DN<4>
C6735  Q_CAP_DIFFBUS  DIFF BUS_0.22UF 6.3V 20% X6S  pkg C0201  page 352 : 1 = P5E_CPU1_P3_TX_BUF_C_DP<5> ; 2 = P5E_CPU1_P3_TX_BUF_DP<5>
C6736  Q_CAP_DIFFBUS  DIFF BUS_0.22UF 6.3V 20% X6S  pkg C0201  page 352 : 1 = P5E_CPU1_P3_TX_BUF_C_DN<5> ; 2 = P5E_CPU1_P3_TX_BUF_DN<5>
C6737  Q_CAP_DIFFBUS  DIFF BUS_0.22UF 6.3V 20% X6S  pkg C0201  page 352 : 1 = P5E_CPU1_P3_TX_BUF_C_DP<6> ; 2 = P5E_CPU1_P3_TX_BUF_DP<6>
C6738  Q_CAP_DIFFBUS  DIFF BUS_0.22UF 6.3V 20% X6S  pkg C0201  page 352 : 1 = P5E_CPU1_P3_TX_BUF_C_DN<6> ; 2 = P5E_CPU1_P3_TX_BUF_DN<6>
C6739  Q_CAP_DIFFBUS  DIFF BUS_0.22UF 6.3V 20% X6S  pkg C0201  page 352 : 1 = P5E_CPU1_P3_TX_BUF_C_DP<7> ; 2 = P5E_CPU1_P3_TX_BUF_DP<7>
C6740  Q_CAP_DIFFBUS  DIFF BUS_0.22UF 6.3V 20% X6S  pkg C0201  page 352 : 1 = P5E_CPU1_P3_TX_BUF_C_DN<7> ; 2 = P5E_CPU1_P3_TX_BUF_DN<7>
C6741  Q_CAP_DIFFBUS  DIFF BUS_0.22UF 6.3V 20% X6S  pkg C0201  page 352 : 1 = P5E_CPU1_P3_TX_BUF_C_DP<8> ; 2 = P5E_CPU1_P3_TX_BUF_DP<8>
C6742  Q_CAP_DIFFBUS  DIFF BUS_0.22UF 6.3V 20% X6S  pkg C0201  page 352 : 1 = P5E_CPU1_P3_TX_BUF_C_DN<8> ; 2 = P5E_CPU1_P3_TX_BUF_DN<8>
C6743  Q_CAP_DIFFBUS  DIFF BUS_0.22UF 6.3V 20% X6S  pkg C0201  page 352 : 1 = P5E_CPU1_P3_TX_BUF_C_DP<9> ; 2 = P5E_CPU1_P3_TX_BUF_DP<9>
C6744  Q_CAP_DIFFBUS  DIFF BUS_0.22UF 6.3V 20% X6S  pkg C0201  page 352 : 1 = P5E_CPU1_P3_TX_BUF_C_DN<9> ; 2 = P5E_CPU1_P3_TX_BUF_DN<9>
C6745  Q_CAP_DIFFBUS  DIFF BUS_0.22UF 6.3V 20% X6S  pkg C0201  page 352 : 1 = P5E_CPU1_P3_TX_BUF_C_DP<10> ; 2 = P5E_CPU1_P3_TX_BUF_DP<10>
C6746  Q_CAP_DIFFBUS  DIFF BUS_0.22UF 6.3V 20% X6S  pkg C0201  page 352 : 1 = P5E_CPU1_P3_TX_BUF_C_DN<10> ; 2 = P5E_CPU1_P3_TX_BUF_DN<10>
C6747  Q_CAP_DIFFBUS  DIFF BUS_0.22UF 6.3V 20% X6S  pkg C0201  page 352 : 1 = P5E_CPU1_P3_TX_BUF_C_DP<11> ; 2 = P5E_CPU1_P3_TX_BUF_DP<11>
C6748  Q_CAP_DIFFBUS  DIFF BUS_0.22UF 6.3V 20% X6S  pkg C0201  page 352 : 1 = P5E_CPU1_P3_TX_BUF_C_DN<11> ; 2 = P5E_CPU1_P3_TX_BUF_DN<11>
C6749  Q_CAP_DIFFBUS  DIFF BUS_0.22UF 6.3V 20% X6S  pkg C0201  page 352 : 1 = P5E_CPU1_P3_TX_BUF_C_DP<12> ; 2 = P5E_CPU1_P3_TX_BUF_DP<12>
C6750  Q_CAP_DIFFBUS  DIFF BUS_0.22UF 6.3V 20% X6S  pkg C0201  page 352 : 1 = P5E_CPU1_P3_TX_BUF_C_DN<12> ; 2 = P5E_CPU1_P3_TX_BUF_DN<12>
C6751  Q_CAP_DIFFBUS  DIFF BUS_0.22UF 6.3V 20% X6S  pkg C0201  page 352 : 1 = P5E_CPU1_P3_TX_BUF_C_DP<13> ; 2 = P5E_CPU1_P3_TX_BUF_DP<13>
C6752  Q_CAP_DIFFBUS  DIFF BUS_0.22UF 6.3V 20% X6S  pkg C0201  page 352 : 1 = P5E_CPU1_P3_TX_BUF_C_DN<13> ; 2 = P5E_CPU1_P3_TX_BUF_DN<13>
C6753  Q_CAP_DIFFBUS  DIFF BUS_0.22UF 6.3V 20% X6S  pkg C0201  page 352 : 1 = P5E_CPU1_P3_TX_BUF_C_DP<14> ; 2 = P5E_CPU1_P3_TX_BUF_DP<14>
C6754  Q_CAP_DIFFBUS  DIFF BUS_0.22UF 6.3V 20% X6S  pkg C0201  page 352 : 1 = P5E_CPU1_P3_TX_BUF_C_DN<14> ; 2 = P5E_CPU1_P3_TX_BUF_DN<14>
C6755  Q_CAP_DIFFBUS  DIFF BUS_0.22UF 6.3V 20% X6S  pkg C0201  page 352 : 1 = P5E_CPU1_P3_TX_BUF_C_DP<15> ; 2 = P5E_CPU1_P3_TX_BUF_DP<15>
C6756  Q_CAP_DIFFBUS  DIFF BUS_0.22UF 6.3V 20% X6S  pkg C0201  page 352 : 1 = P5E_CPU1_P3_TX_BUF_C_DN<15> ; 2 = P5E_CPU1_P3_TX_BUF_DN<15>
C6757  Q_CAP  0.1UF 25V 10% EMPTY  pkg 0402  page 360 : 1 = P1V8_RETIMER_CPU0_EN ; 2 = GND
C6758  Q_CAP  1000PF 50V 5% X7R  pkg 0402  page 360 : 1 = FM_PWRGD_P1V8_RETIMER_CPU0 ; 2 = GND
C7000  Q_CAPP  470UF 2.5V 20% SPCAP  pkg SMLF  page 279 : 1 = P0V9_CPU0_RT_2D ; 2 = GND
C7001  Q_CAPP  470UF 2.5V 20% SPCAP  pkg SMLF  page 279 : 1 = P0V9_CPU0_RT_2D ; 2 = GND
C7002  Q_CAP  47UF 4V 20% X6S  pkg C0805  page 279 : 1 = P0V9_CPU0_RT_2D ; 2 = GND
C7003  Q_CAP  47UF 4V 20% X6S  pkg C0805  page 279 : 1 = P0V9_CPU0_RT_2D ; 2 = GND
C7004  Q_CAPP  470UF 2.5V 20% SPCAP  pkg SMLF  page 345 : 1 = P0V9_CPU1_RT_2D ; 2 = GND
C7005  Q_CAPP  470UF 2.5V 20% SPCAP  pkg SMLF  page 345 : 1 = P0V9_CPU1_RT_2D ; 2 = GND
C7006  Q_CAP  47UF 4V 20% X6S  pkg C0805  page 345 : 1 = P0V9_CPU1_RT_2D ; 2 = GND
C7007  Q_CAP  47UF 4V 20% X6S  pkg C0805  page 345 : 1 = P0V9_CPU1_RT_2D ; 2 = GND
C7008  Q_CAPP  470UF 2.5V 20% SPCAP  pkg SMLF  page 279 : 1 = P0V9_CPU0_RT0_2A ; 2 = GND
C7009  Q_CAPP  470UF 2.5V 20% SPCAP  pkg SMLF  page 279 : 1 = P0V9_CPU0_RT0_2A ; 2 = GND
C7010  Q_CAP  100UF 4V 20% X6S  pkg C0805  page 279 : 1 = P0V9_CPU0_RT0_2A ; 2 = GND
C7011  Q_CAPP  470UF 2.5V 20% SPCAP  pkg SMLF  page 290 : 1 = P0V9_CPU0_RT1_2A ; 2 = GND
C7012  Q_CAPP  470UF 2.5V 20% SPCAP  pkg SMLF  page 290 : 1 = P0V9_CPU0_RT1_2A ; 2 = GND
C7013  Q_CAP  100UF 4V 20% X6S  pkg C0805  page 290 : 1 = P0V9_CPU0_RT1_2A ; 2 = GND
